# T6G (Grand Teton) — schematic netlist excerpt (pin names and nets, part order shuffled) for the footprints in the layout excerpt that follows; sources: Cadence DE-HDL packaged netlist, KiCad conversion of 04192023_DAF0TMB3IC0_F0TG_MB_C_brd_V02_OCP.brd

C270  Q_CAP  22UF 4V 20% X6S  pkg C0402  page 69 : A = PVDDCR_CPU0_P0 ; B = GND
R574  Q_RES  0 5% EMPTY  pkg 0402LF  page 55 : A = XTAL_CPU1_R_X32K_X1 ; B = XTAL_CPU1_X32K_X1

(kicad_pcb
	(version 20260206)
	(generator "pcbnew")
	(generator_version "10.0")
	(general
		(thickness 1.6)
		(legacy_teardrops no)
	)
	(paper "A4")
	(title_block
		(title "04192023_DAF0TMB3IC0_F0TG_MB_C_brd_V02_OCP.brd")
		(comment 1 "Grand Teton / footprints 6940-6941 of 8354")
	)
	(layers
		(0 "F.Cu" signal "TOP")
		(4 "In1.Cu" signal "GND")
		(6 "In2.Cu" signal "IN1")
		(8 "In3.Cu" signal "GND1")
		(10 "In4.Cu" signal "IN2")
		(12 "In5.Cu" signal "GND2")
		(14 "In6.Cu" signal "IN3")
		(16 "In7.Cu" signal "GND3")
		(18 "In8.Cu" signal "VCC")
		(20 "In9.Cu" signal "VCC1")
		(22 "In10.Cu" signal "GND4")
		(24 "In11.Cu" signal "IN4")
		(26 "In12.Cu" signal "GND5")
		(28 "In13.Cu" signal "IN5")
		(30 "In14.Cu" signal "GND6")
		(32 "In15.Cu" signal "IN6")
		(34 "In16.Cu" signal "GND7")
		(2 "B.Cu" signal "BOTTOM")
		(9 "F.Adhes" user "F.Adhesive")
		(11 "B.Adhes" user "B.Adhesive")
		(13 "F.Paste" user "Package Geometry/Pastemask Top")
		(15 "B.Paste" user "Package Geometry/Pastemask Bottom")
		(5 "F.SilkS" user "Ref Des/Silkscreen Top")
		(7 "B.SilkS" user "Ref Des/Silkscreen Bottom")
		(1 "F.Mask" user "Board Geometry/Soldermask Top")
		(3 "B.Mask" user "Board Geometry/Soldermask Bottom")
		(17 "Dwgs.User" user "User.Drawings")
		(19 "Cmts.User" user "User.Comments")
		(21 "Eco1.User" user "User.Eco1")
		(23 "Eco2.User" user "User.Eco2")
		(25 "Edge.Cuts" user "Board Geometry/Outline")
		(27 "Margin" user)
		(31 "F.CrtYd" user "Package Geometry/Place Bound Top")
		(29 "B.CrtYd" user "Package Geometry/Place Bound Bottom")
		(35 "F.Fab" user "Ref Des/Assembly Top")
		(33 "B.Fab" user "Ref Des/Assembly Bottom")
	)
	(footprint ""
		(layer "B.Cu")
		(at 152.959054 -313.96305 90)
		(property "Reference" "R574"
			(at 0 0 90)
			(layer "B.SilkS")
			(hide yes)
			(effects
				(font
					(size 1.27 1.27)
				)
				(justify mirror)
			)
		)
		(property "Value" ""
			(at 0 0 90)
			(layer "B.Fab")
			(effects
				(font
					(size 1.27 1.27)
				)
				(justify mirror)
			)
		)
		(duplicate_pad_numbers_are_jumpers no)
		(fp_line
			(start 0.7874 -0.4064)
			(end -0.7874 -0.4064)
			(stroke
				(width 0.1524)
				(type default)
			)
			(layer "B.SilkS")
		)
		(fp_line
			(start -0.7874 -0.4064)
			(end -0.7874 0.4064)
			(stroke
				(width 0.1524)
				(type default)
			)
			(layer "B.SilkS")
		)
		(fp_line
			(start 0.7874 0.4064)
			(end 0.7874 -0.4064)
			(stroke
				(width 0.1524)
				(type default)
			)
			(layer "B.SilkS")
		)
		(fp_line
			(start -0.7874 0.4064)
			(end 0.7874 0.4064)
			(stroke
				(width 0.1524)
				(type default)
			)
			(layer "B.SilkS")
		)
		(fp_line
			(start 0.67945 -0.305054)
			(end 0.12065 -0.305054)
			(stroke
				(width 0.1)
				(type default)
			)
			(layer "B.Fab")
		)
		(fp_line
			(start 0.12065 -0.305054)
			(end 0.12065 -0.2794)
			(stroke
				(width 0.1)
				(type default)
			)
			(layer "B.Fab")
		)
		(fp_line
			(start -0.12065 -0.3048)
			(end -0.67945 -0.3048)
			(stroke
				(width 0.1)
				(type default)
			)
			(layer "B.Fab")
		)
		(fp_line
			(start -0.67945 -0.3048)
			(end -0.67945 0.3048)
			(stroke
				(width 0.1)
				(type default)
			)
			(layer "B.Fab")
		)
		(fp_line
			(start 0.12065 -0.2794)
			(end -0.12065 -0.2794)
			(stroke
				(width 0.1)
				(type default)
			)
			(layer "B.Fab")
		)
		(fp_line
			(start -0.12065 -0.2794)
			(end -0.12065 -0.3048)
			(stroke
				(width 0.1)
				(type default)
			)
			(layer "B.Fab")
		)
		(fp_line
			(start 0.12065 0.2794)
			(end 0.12065 0.3048)
			(stroke
				(width 0.1)
				(type default)
			)
			(layer "B.Fab")
		)
		(fp_line
			(start -0.120396 0.2794)
			(end 0.12065 0.2794)
			(stroke
				(width 0.1)
				(type default)
			)
			(layer "B.Fab")
		)
		(fp_line
			(start 0.67945 0.3048)
			(end 0.67945 -0.305054)
			(stroke
				(width 0.1)
				(type default)
			)
			(layer "B.Fab")
		)
		(fp_line
			(start 0.12065 0.3048)
			(end 0.67945 0.3048)
			(stroke
				(width 0.1)
				(type default)
			)
			(layer "B.Fab")
		)
		(fp_line
			(start -0.120396 0.3048)
			(end -0.120396 0.2794)
			(stroke
				(width 0.1)
				(type default)
			)
			(layer "B.Fab")
		)
		(fp_line
			(start -0.67945 0.3048)
			(end -0.120396 0.3048)
			(stroke
				(width 0.1)
				(type default)
			)
			(layer "B.Fab")
		)
		(pad "1" smd circle
			(at 0.40005 0 270)
			(size 0 0)
			(layers "B.Cu" "B.Mask" "B.Paste")
			(net "XTAL_CPU1_R_X32K_X1")
		)
		(pad "2" smd circle
			(at -0.40005 0 270)
			(size 0 0)
			(layers "B.Cu" "B.Mask" "B.Paste")
			(net "XTAL_CPU1_X32K_X1")
		)
	)
	(footprint ""
		(layer "B.Cu")
		(at 356.081838 -250.25731)
		(property "Reference" "C270"
			(at 0 0 0)
			(layer "B.SilkS")
			(hide yes)
			(effects
				(font
					(size 1.27 1.27)
				)
				(justify mirror)
			)
		)
		(property "Value" ""
			(at 0 0 0)
			(layer "B.Fab")
			(effects
				(font
					(size 1.27 1.27)
				)
				(justify mirror)
			)
		)
		(duplicate_pad_numbers_are_jumpers no)
		(fp_line
			(start -0.7874 -0.4064)
			(end -0.7874 0.4064)
			(stroke
				(width 0.1524)
				(type default)
			)
			(layer "B.SilkS")
		)
		(fp_line
			(start -0.7874 0.4064)
			(end 0.7874 0.4064)
			(stroke
				(width 0.1524)
				(type default)
			)
			(layer "B.SilkS")
		)
		(fp_line
			(start 0.7874 -0.4064)
			(end -0.7874 -0.4064)
			(stroke
				(width 0.1524)
				(type default)
			)
			(layer "B.SilkS")
		)
		(fp_line
			(start 0.7874 0.4064)
			(end 0.7874 -0.4064)
			(stroke
				(width 0.1524)
				(type default)
			)
			(layer "B.SilkS")
		)
		(fp_line
			(start -0.67945 -0.3048)
			(end -0.67945 0.3048)
			(stroke
				(width 0.1)
				(type default)
			)
			(layer "B.Fab")
		)
		(fp_line
			(start -0.67945 0.3048)
			(end -0.120396 0.3048)
			(stroke
				(width 0.1)
				(type default)
			)
			(layer "B.Fab")
		)
		(fp_line
			(start -0.12065 -0.3048)
			(end -0.67945 -0.3048)
			(stroke
				(width 0.1)
				(type default)
			)
			(layer "B.Fab")
		)
		(fp_line
			(start -0.12065 -0.2794)
			(end -0.12065 -0.3048)
			(stroke
				(width 0.1)
				(type default)
			)
			(layer "B.Fab")
		)
		(fp_line
			(start -0.120396 0.2794)
			(end 0.12065 0.2794)
			(stroke
				(width 0.1)
				(type default)
			)
			(layer "B.Fab")
		)
		(fp_line
			(start -0.120396 0.3048)
			(end -0.120396 0.2794)
			(stroke
				(width 0.1)
				(type default)
			)
			(layer "B.Fab")
		)
		(fp_line
			(start 0.12065 -0.305054)
			(end 0.12065 -0.2794)
			(stroke
				(width 0.1)
				(type default)
			)
			(layer "B.Fab")
		)
		(fp_line
			(start 0.12065 -0.2794)
			(end -0.12065 -0.2794)
			(stroke
				(width 0.1)
				(type default)
			)
			(layer "B.Fab")
		)
		(fp_line
			(start 0.12065 0.2794)
			(end 0.12065 0.3048)
			(stroke
				(width 0.1)
				(type default)
			)
			(layer "B.Fab")
		)
		(fp_line
			(start 0.12065 0.3048)
			(end 0.67945 0.3048)
			(stroke
				(width 0.1)
				(type default)
			)
			(layer "B.Fab")
		)
		(fp_line
			(start 0.67945 -0.305054)
			(end 0.12065 -0.305054)
			(stroke
				(width 0.1)
				(type default)
			)
			(layer "B.Fab")
		)
		(fp_line
			(start 0.67945 0.3048)
			(end 0.67945 -0.305054)
			(stroke
				(width 0.1)
				(type default)
			)
			(layer "B.Fab")
		)
		(pad "1" smd circle
			(at 0.40005 0 180)
			(size 0 0)
			(layers "B.Cu" "B.Mask" "B.Paste")
			(net "PVDDCR_CPU0_P0")
		)
		(pad "2" smd circle
			(at -0.40005 0 180)
			(size 0 0)
			(layers "B.Cu" "B.Mask" "B.Paste")
			(net "GND")
		)
	)
)
